(kicad_pcb
	(version 20260206)
	(generator "pcbnew")
	(generator_version "10.0")
	(general
		(thickness 1.6)
		(legacy_teardrops no)
	)
	(paper "A4")
	(title_block
		(title "9054_F0T_PDB_BD_GPU_F_V04_1213_1550_OCP.brd")
		(comment 1 "Grand Teton / footprints 379-380 of 608")
	)
	(layers
		(0 "F.Cu" signal "TOP")
		(4 "In1.Cu" signal "GND")
		(6 "In2.Cu" signal "IN1")
		(8 "In3.Cu" signal "GND1")
		(10 "In4.Cu" signal "VCC")
		(12 "In5.Cu" signal "VCC1")
		(14 "In6.Cu" signal "GND2")
		(16 "In7.Cu" signal "IN2")
		(18 "In8.Cu" signal "GND3")
		(2 "B.Cu" signal "BOTTOM")
		(9 "F.Adhes" user "F.Adhesive")
		(11 "B.Adhes" user "B.Adhesive")
		(13 "F.Paste" user "Package Geometry/Pastemask Top")
		(15 "B.Paste" user "Package Geometry/Pastemask Bottom")
		(5 "F.SilkS" user "Ref Des/Silkscreen Top")
		(7 "B.SilkS" user "Ref Des/Silkscreen Bottom")
		(1 "F.Mask" user "Board Geometry/Soldermask Top")
		(3 "B.Mask" user "Board Geometry/Soldermask Bottom")
		(17 "Dwgs.User" user "User.Drawings")
		(19 "Cmts.User" user "User.Comments")
		(21 "Eco1.User" user "User.Eco1")
		(23 "Eco2.User" user "User.Eco2")
		(25 "Edge.Cuts" user "Board Geometry/Outline")
		(27 "Margin" user)
		(31 "F.CrtYd" user "Package Geometry/Place Bound Top")
		(29 "B.CrtYd" user "Package Geometry/Place Bound Bottom")
		(35 "F.Fab" user "Ref Des/Assembly Top")
		(33 "B.Fab" user "Ref Des/Assembly Bottom")
	)
	(footprint ""
		(layer "F.Cu")
		(at 238.810038 -51.049936 180)
		(property "Reference" "J6"
			(at 0.913638 -41.905936 0)
			(unlocked yes)
			(layer "F.SilkS")
			(effects
				(font
					(size 10.16 7.62)
					(thickness 1.778)
				)
			)
		)
		(property "Value" ""
			(at 0 0 180)
			(layer "F.Fab")
			(effects
				(font
					(size 1.27 1.27)
				)
			)
		)
		(duplicate_pad_numbers_are_jumpers no)
		(fp_line
			(start 14.109954 34.36493)
			(end -6.469888 34.36493)
			(stroke
				(width 0.1524)
				(type default)
			)
			(layer "F.SilkS")
		)
		(fp_line
			(start 14.109954 -34.36493)
			(end 14.109954 34.36493)
			(stroke
				(width 0.1524)
				(type default)
			)
			(layer "F.SilkS")
		)
		(fp_line
			(start 11.10996 31.364936)
			(end 4.241038 31.364936)
			(stroke
				(width 0.1524)
				(type default)
			)
			(layer "F.SilkS")
		)
		(fp_line
			(start 11.10996 -31.364936)
			(end 11.10996 31.364936)
			(stroke
				(width 0.1524)
				(type default)
			)
			(layer "F.SilkS")
		)
		(fp_line
			(start 4.291838 -31.364936)
			(end 11.10996 -31.364936)
			(stroke
				(width 0.1524)
				(type default)
			)
			(layer "F.SilkS")
		)
		(fp_line
			(start -3.469894 25.912064)
			(end -3.469894 -25.370536)
			(stroke
				(width 0.1524)
				(type default)
			)
			(layer "F.SilkS")
		)
		(fp_line
			(start -6.469888 34.36493)
			(end -6.469888 -34.36493)
			(stroke
				(width 0.1524)
				(type default)
			)
			(layer "F.SilkS")
		)
		(fp_line
			(start -6.469888 -34.36493)
			(end 14.109954 -34.36493)
			(stroke
				(width 0.1524)
				(type default)
			)
			(layer "F.SilkS")
		)
		(fp_poly
			(pts
				(xy -5.0038 -0.508) (xy -5.0038 0.508) (xy -3.9878 0)
			)
			(stroke
				(width 0)
				(type default)
			)
			(fill yes)
			(layer "F.SilkS")
		)
		(fp_line
			(start 14.109954 34.36493)
			(end -6.469888 34.36493)
			(stroke
				(width 0.1524)
				(type default)
			)
			(layer "B.SilkS")
		)
		(fp_line
			(start 14.109954 -34.36493)
			(end 14.109954 34.36493)
			(stroke
				(width 0.1524)
				(type default)
			)
			(layer "B.SilkS")
		)
		(fp_line
			(start -6.469888 34.36493)
			(end -6.469888 -34.36493)
			(stroke
				(width 0.1524)
				(type default)
			)
			(layer "B.SilkS")
		)
		(fp_line
			(start -6.469888 -34.36493)
			(end 14.109954 -34.36493)
			(stroke
				(width 0.1524)
				(type default)
			)
			(layer "B.SilkS")
		)
		(fp_line
			(start 14.109954 34.36493)
			(end -6.469888 34.36493)
			(stroke
				(width 0.1)
				(type default)
			)
			(layer "B.Fab")
		)
		(fp_line
			(start 14.109954 -34.36493)
			(end 14.109954 34.36493)
			(stroke
				(width 0.1)
				(type default)
			)
			(layer "B.Fab")
		)
		(fp_line
			(start -6.469888 34.36493)
			(end -6.469888 -34.36493)
			(stroke
				(width 0.1)
				(type default)
			)
			(layer "B.Fab")
		)
		(fp_line
			(start -6.469888 -34.36493)
			(end 14.109954 -34.36493)
			(stroke
				(width 0.1)
				(type default)
			)
			(layer "B.Fab")
		)
		(fp_line
			(start 11.10996 31.364936)
			(end -3.469894 31.364936)
			(stroke
				(width 0.1)
				(type default)
			)
			(layer "F.Fab")
		)
		(fp_line
			(start 11.10996 -31.364936)
			(end 11.10996 31.364936)
			(stroke
				(width 0.1)
				(type default)
			)
			(layer "F.Fab")
		)
		(fp_line
			(start -3.469894 31.364936)
			(end -3.469894 -31.364936)
			(stroke
				(width 0.1)
				(type default)
			)
			(layer "F.Fab")
		)
		(fp_line
			(start -3.469894 -31.364936)
			(end 11.10996 -31.364936)
			(stroke
				(width 0.1)
				(type default)
			)
			(layer "F.Fab")
		)
		(fp_poly
			(pts
				(xy -5.0038 -0.508) (xy -5.0038 0.508) (xy -3.9878 0)
			)
			(stroke
				(width 0)
				(type default)
			)
			(fill yes)
			(layer "F.Fab")
		)
		(fp_text user "PRESS-FIT"
			(at 12.63015 -0.0127 90)
			(unlocked yes)
			(layer "F.SilkS")
			(effects
				(font
					(size 1.905 1.4224)
					(thickness 0.1524)
				)
			)
		)
		(fp_text user "PRESS-FIT"
			(at 12.629388 0.639064 270)
			(unlocked yes)
			(layer "B.SilkS")
			(effects
				(font
					(size 1.905 1.4224)
					(thickness 0.1524)
				)
				(justify mirror)
			)
		)
		(fp_text user "PRESS-FIT"
			(at 12.63015 -0.0127 90)
			(unlocked yes)
			(layer "B.Fab")
			(effects
				(font
					(size 1.905 1.4224)
					(thickness 0.1524)
				)
				(justify mirror)
			)
		)
		(fp_text user "PRESS-FIT"
			(at 12.63015 -0.0127 90)
			(unlocked yes)
			(layer "F.Fab")
			(effects
				(font
					(size 1.905 1.4224)
					(thickness 0.1524)
				)
			)
		)
		(pad "" np_thru_hole circle
			(at 0 -28.575 180)
			(size 0 0)
			(drill 3.2004)
			(layers "*.Cu" "*.Mask")
			(clearance 0)
		)
		(pad "" np_thru_hole circle
			(at 0 28.575 180)
			(size 0 0)
			(drill 3.2004)
			(layers "*.Cu" "*.Mask")
			(clearance 0)
		)
		(pad "A1" thru_hole rect
			(at 0 0 180)
			(size 1.52781 1.52781)
			(drill 1.01981)
			(layers "*.Cu" "*.Mask")
			(remove_unused_layers no)
			(net "P52V_1_BUSBAR")
			(clearance 0)
			(padstack
				(mode front_inner_back)
				(layer "Inner"
					(shape circle)
					(size 1.52781 1.52781)
					(clearance 0)
				)
				(layer "B.Cu"
					(shape rect)
					(size 1.52781 1.52781)
					(clearance 0)
				)
			)
		)
		(pad "B1" thru_hole circle
			(at 2.54 0 180)
			(size 1.52781 1.52781)
			(drill 1.01981)
			(layers "*.Cu" "*.Mask")
			(remove_unused_layers no)
			(net "GND_1_BUSBAR")
			(clearance 0)
		)
		(pad "C1" thru_hole circle
			(at 5.08 0 180)
			(size 1.52781 1.52781)
			(drill 1.01981)
			(layers "*.Cu" "*.Mask")
			(remove_unused_layers no)
			(net "NC_J6_C1")
			(clearance 0)
		)
		(pad "D1" thru_hole circle
			(at 7.62 0 180)
			(size 1.52781 1.52781)
			(drill 1.01981)
			(layers "*.Cu" "*.Mask")
			(remove_unused_layers no)
			(net "NC_J6_D1")
			(clearance 0)
		)
		(pad "P1_1" thru_hole circle
			(at 7.62 -16.51 180)
			(size 1.52781 1.52781)
			(drill 1.01981)
			(layers "*.Cu" "*.Mask")
			(remove_unused_layers no)
			(net "P52V_1")
			(clearance 0)
		)
		(pad "P1_2" thru_hole circle
			(at 5.08 -16.51 180)
			(size 1.52781 1.52781)
			(drill 1.01981)
			(layers "*.Cu" "*.Mask")
			(remove_unused_layers no)
			(net "P52V_1")
			(clearance 0)
		)
		(pad "P1_3" thru_hole circle
			(at 2.54 -16.51 180)
			(size 1.52781 1.52781)
			(drill 1.01981)
			(layers "*.Cu" "*.Mask")
			(remove_unused_layers no)
			(net "P52V_1")
			(clearance 0)
		)
		(pad "P1_4" thru_hole circle
			(at 0 -16.51 180)
			(size 1.52781 1.52781)
			(drill 1.01981)
			(layers "*.Cu" "*.Mask")
			(remove_unused_layers no)
			(net "P52V_1")
			(clearance 0)
		)
		(pad "P1_5" thru_hole circle
			(at 7.62 -13.97 180)
			(size 1.52781 1.52781)
			(drill 1.01981)
			(layers "*.Cu" "*.Mask")
			(remove_unused_layers no)
			(net "P52V_1")
			(clearance 0)
		)
		(pad "P1_6" thru_hole circle
			(at 5.08 -13.97 180)
			(size 1.52781 1.52781)
			(drill 1.01981)
			(layers "*.Cu" "*.Mask")
			(remove_unused_layers no)
			(net "P52V_1")
			(clearance 0)
		)
		(pad "P1_7" thru_hole circle
			(at 2.54 -13.97 180)
			(size 1.52781 1.52781)
			(drill 1.01981)
			(layers "*.Cu" "*.Mask")
			(remove_unused_layers no)
			(net "P52V_1")
			(clearance 0)
		)
		(pad "P1_8" thru_hole circle
			(at 0 -13.97 180)
			(size 1.52781 1.52781)
			(drill 1.01981)
			(layers "*.Cu" "*.Mask")
			(remove_unused_layers no)
			(net "P52V_1")
			(clearance 0)
		)
		(pad "P2_1" thru_hole circle
			(at 7.62 -7.62 180)
			(size 1.52781 1.52781)
			(drill 1.01981)
			(layers "*.Cu" "*.Mask")
			(remove_unused_layers no)
			(net "P52V_1")
			(clearance 0)
		)
		(pad "P2_2" thru_hole circle
			(at 5.08 -7.62 180)
			(size 1.52781 1.52781)
			(drill 1.01981)
			(layers "*.Cu" "*.Mask")
			(remove_unused_layers no)
			(net "P52V_1")
			(clearance 0)
		)
		(pad "P2_3" thru_hole circle
			(at 2.54 -7.62 180)
			(size 1.52781 1.52781)
			(drill 1.01981)
			(layers "*.Cu" "*.Mask")
			(remove_unused_layers no)
			(net "P52V_1")
			(clearance 0)
		)
		(pad "P2_4" thru_hole circle
			(at 0 -7.62 180)
			(size 1.52781 1.52781)
			(drill 1.01981)
			(layers "*.Cu" "*.Mask")
			(remove_unused_layers no)
			(net "P52V_1")
			(clearance 0)
		)
		(pad "P2_5" thru_hole circle
			(at 7.62 -5.08 180)
			(size 1.52781 1.52781)
			(drill 1.01981)
			(layers "*.Cu" "*.Mask")
			(remove_unused_layers no)
			(net "P52V_1")
			(clearance 0)
		)
		(pad "P2_6" thru_hole circle
			(at 5.08 -5.08 180)
			(size 1.52781 1.52781)
			(drill 1.01981)
			(layers "*.Cu" "*.Mask")
			(remove_unused_layers no)
			(net "P52V_1")
			(clearance 0)
		)
		(pad "P2_7" thru_hole circle
			(at 2.54 -5.08 180)
			(size 1.52781 1.52781)
			(drill 1.01981)
			(layers "*.Cu" "*.Mask")
			(remove_unused_layers no)
			(net "P52V_1")
			(clearance 0)
		)
		(pad "P2_8" thru_hole circle
			(at 0 -5.08 180)
			(size 1.52781 1.52781)
			(drill 1.01981)
			(layers "*.Cu" "*.Mask")
			(remove_unused_layers no)
			(net "P52V_1")
			(clearance 0)
		)
		(pad "P3_1" thru_hole circle
			(at 7.62 5.08 180)
			(size 1.52781 1.52781)
			(drill 1.01981)
			(layers "*.Cu" "*.Mask")
			(remove_unused_layers no)
			(net "GND")
			(clearance 0)
		)
		(pad "P3_2" thru_hole circle
			(at 5.08 5.08 180)
			(size 1.52781 1.52781)
			(drill 1.01981)
			(layers "*.Cu" "*.Mask")
			(remove_unused_layers no)
			(net "GND")
			(clearance 0)
		)
		(pad "P3_3" thru_hole circle
			(at 2.54 5.08 180)
			(size 1.52781 1.52781)
			(drill 1.01981)
			(layers "*.Cu" "*.Mask")
			(remove_unused_layers no)
			(net "GND")
			(clearance 0)
		)
		(pad "P3_4" thru_hole circle
			(at 0 5.08 180)
			(size 1.52781 1.52781)
			(drill 1.01981)
			(layers "*.Cu" "*.Mask")
			(remove_unused_layers no)
			(net "GND")
			(clearance 0)
		)
		(pad "P3_5" thru_hole circle
			(at 7.62 7.62 180)
			(size 1.52781 1.52781)
			(drill 1.01981)
			(layers "*.Cu" "*.Mask")
			(remove_unused_layers no)
			(net "GND")
			(clearance 0)
		)
		(pad "P3_6" thru_hole circle
			(at 5.08 7.62 180)
			(size 1.52781 1.52781)
			(drill 1.01981)
			(layers "*.Cu" "*.Mask")
			(remove_unused_layers no)
			(net "GND")
			(clearance 0)
		)
		(pad "P3_7" thru_hole circle
			(at 2.54 7.62 180)
			(size 1.52781 1.52781)
			(drill 1.01981)
			(layers "*.Cu" "*.Mask")
			(remove_unused_layers no)
			(net "GND")
			(clearance 0)
		)
		(pad "P3_8" thru_hole circle
			(at 0 7.62 180)
			(size 1.52781 1.52781)
			(drill 1.01981)
			(layers "*.Cu" "*.Mask")
			(remove_unused_layers no)
			(net "GND")
			(clearance 0)
		)
		(pad "P4_1" thru_hole circle
			(at 7.62 13.97 180)
			(size 1.52781 1.52781)
			(drill 1.01981)
			(layers "*.Cu" "*.Mask")
			(remove_unused_layers no)
			(net "GND")
			(clearance 0)
		)
		(pad "P4_2" thru_hole circle
			(at 5.08 13.97 180)
			(size 1.52781 1.52781)
			(drill 1.01981)
			(layers "*.Cu" "*.Mask")
			(remove_unused_layers no)
			(net "GND")
			(clearance 0)
		)
		(pad "P4_3" thru_hole circle
			(at 2.54 13.97 180)
			(size 1.52781 1.52781)
			(drill 1.01981)
			(layers "*.Cu" "*.Mask")
			(remove_unused_layers no)
			(net "GND")
			(clearance 0)
		)
		(pad "P4_4" thru_hole circle
			(at 0 13.97 180)
			(size 1.52781 1.52781)
			(drill 1.01981)
			(layers "*.Cu" "*.Mask")
			(remove_unused_layers no)
			(net "GND")
			(clearance 0)
		)
		(pad "P4_5" thru_hole circle
			(at 7.62 16.51 180)
			(size 1.52781 1.52781)
			(drill 1.01981)
			(layers "*.Cu" "*.Mask")
			(remove_unused_layers no)
			(net "GND")
			(clearance 0)
		)
		(pad "P4_6" thru_hole circle
			(at 5.08 16.51 180)
			(size 1.52781 1.52781)
			(drill 1.01981)
			(layers "*.Cu" "*.Mask")
			(remove_unused_layers no)
			(net "GND")
			(clearance 0)
		)
		(pad "P4_7" thru_hole circle
			(at 2.54 16.51 180)
			(size 1.52781 1.52781)
			(drill 1.01981)
			(layers "*.Cu" "*.Mask")
			(remove_unused_layers no)
			(net "GND")
			(clearance 0)
		)
		(pad "P4_8" thru_hole circle
			(at 0 16.51 180)
			(size 1.52781 1.52781)
			(drill 1.01981)
			(layers "*.Cu" "*.Mask")
			(remove_unused_layers no)
			(net "GND")
			(clearance 0)
		)
		(zone
			(layers "F.Cu" "B.Cu" "In1.Cu" "In2.Cu" "In3.Cu" "In4.Cu" "In5.Cu" "In6.Cu"
				"In7.Cu" "In8.Cu"
			)
			(hatch none 0.5)
			(connect_pads
				(clearance 0)
			)
			(min_thickness 0.25)
			(keepout
				(tracks not_allowed)
				(vias allowed)
				(pads allowed)
				(copperpour not_allowed)
				(footprints allowed)
			)
			(placement
				(enabled no)
				(sheetname "")
			)
			(fill
				(thermal_gap 0.5)
				(thermal_bridge_width 0.5)
				(island_removal_mode 0)
			)
			(polygon
				(pts
					(arc
						(start 242.442238 -79.624936)
						(mid 235.177838 -79.624936)
						(end 242.442238 -79.624936)
					)
				)
			)
		)
		(zone
			(layers "F.Cu" "B.Cu" "In1.Cu" "In2.Cu" "In3.Cu" "In4.Cu" "In5.Cu" "In6.Cu"
				"In7.Cu" "In8.Cu"
			)
			(hatch none 0.5)
			(connect_pads
				(clearance 0)
			)
			(min_thickness 0.25)
			(keepout
				(tracks not_allowed)
				(vias allowed)
				(pads allowed)
				(copperpour not_allowed)
				(footprints allowed)
			)
			(placement
				(enabled no)
				(sheetname "")
			)
			(fill
				(thermal_gap 0.5)
				(thermal_bridge_width 0.5)
				(island_removal_mode 0)
			)
			(polygon
				(pts
					(arc
						(start 242.442238 -22.474936)
						(mid 235.177838 -22.474936)
						(end 242.442238 -22.474936)
					)
				)
			)
		)
		(zone
			(layer "B.Cu")
			(hatch none 0.5)
			(connect_pads
				(clearance 0)
			)
			(min_thickness 0.25)
			(keepout
				(tracks allowed)
				(vias not_allowed)
				(pads allowed)
				(copperpour not_allowed)
				(footprints allowed)
			)
			(placement
				(enabled no)
				(sheetname "")
			)
			(fill
				(thermal_gap 0.5)
				(thermal_bridge_width 0.5)
				(island_removal_mode 0)
			)
			(polygon
				(pts
					(xy 239.637316 -33.712658) (xy 239.637316 -68.387214) (xy 230.36276 -68.387214) (xy 230.36276 -33.712658)
				)
			)
		)
	)
	(footprint ""
		(layer "F.Cu")
		(at 145.11782 -34.3662 180)
		(property "Reference" "PR6987"
			(at 0 0 180)
			(layer "F.SilkS")
			(hide yes)
			(effects
				(font
					(size 1.27 1.27)
				)
			)
		)
		(property "Value" ""
			(at 0 0 180)
			(layer "F.Fab")
			(effects
				(font
					(size 1.27 1.27)
				)
			)
		)
		(duplicate_pad_numbers_are_jumpers no)
		(fp_line
			(start 1.2954 0.5842)
			(end -1.2954 0.5842)
			(stroke
				(width 0.1524)
				(type default)
			)
			(layer "F.SilkS")
		)
		(fp_line
			(start 1.2954 -0.5842)
			(end 1.2954 0.5842)
			(stroke
				(width 0.1524)
				(type default)
			)
			(layer "F.SilkS")
		)
		(fp_line
			(start -1.2954 0.5842)
			(end -1.2954 -0.5842)
			(stroke
				(width 0.1524)
				(type default)
			)
			(layer "F.SilkS")
		)
		(fp_line
			(start -1.2954 -0.5842)
			(end 1.2954 -0.5842)
			(stroke
				(width 0.1524)
				(type default)
			)
			(layer "F.SilkS")
		)
		(fp_line
			(start 1.1938 0.4064)
			(end 0.8636 0.4064)
			(stroke
				(width 0.1)
				(type default)
			)
			(layer "F.Fab")
		)
		(fp_line
			(start 1.1938 -0.406654)
			(end 1.1938 0.4064)
			(stroke
				(width 0.1)
				(type default)
			)
			(layer "F.Fab")
		)
		(fp_line
			(start 0.8636 0.4572)
			(end -0.8636 0.4572)
			(stroke
				(width 0.1)
				(type default)
			)
			(layer "F.Fab")
		)
		(fp_line
			(start 0.8636 0.4064)
			(end 0.8636 0.4572)
			(stroke
				(width 0.1)
				(type default)
			)
			(layer "F.Fab")
		)
		(fp_line
			(start 0.8636 -0.406654)
			(end 1.1938 -0.406654)
			(stroke
				(width 0.1)
				(type default)
			)
			(layer "F.Fab")
		)
		(fp_line
			(start 0.8636 -0.4572)
			(end 0.8636 -0.406654)
			(stroke
				(width 0.1)
				(type default)
			)
			(layer "F.Fab")
		)
		(fp_line
			(start -0.8636 0.4572)
			(end -0.8636 0.4318)
			(stroke
				(width 0.1)
				(type default)
			)
			(layer "F.Fab")
		)
		(fp_line
			(start -0.8636 0.4318)
			(end -0.8636 0.4064)
			(stroke
				(width 0.1)
				(type default)
			)
			(layer "F.Fab")
		)
		(fp_line
			(start -0.8636 0.4064)
			(end -1.1938 0.4064)
			(stroke
				(width 0.1)
				(type default)
			)
			(layer "F.Fab")
		)
		(fp_line
			(start -0.8636 -0.406654)
			(end -0.8636 -0.4572)
			(stroke
				(width 0.1)
				(type default)
			)
			(layer "F.Fab")
		)
		(fp_line
			(start -0.8636 -0.4572)
			(end 0.8636 -0.4572)
			(stroke
				(width 0.1)
				(type default)
			)
			(layer "F.Fab")
		)
		(fp_line
			(start -1.1938 0.4064)
			(end -1.1938 -0.406654)
			(stroke
				(width 0.1)
				(type default)
			)
			(layer "F.Fab")
		)
		(fp_line
			(start -1.1938 -0.406654)
			(end -0.8636 -0.406654)
			(stroke
				(width 0.1)
				(type default)
			)
			(layer "F.Fab")
		)
		(pad "1" smd rect
			(at -0.7366 0 90)
			(size 0.7112 0.8128)
			(layers "F.Cu" "F.Mask" "F.Paste")
			(net "P52V_HS2_SENSE_P_R2")
		)
		(pad "2" smd rect
			(at 0.7366 0 90)
			(size 0.7112 0.8128)
			(layers "F.Cu" "F.Mask" "F.Paste")
			(net "P52V_HS2_4287_ADC_P")
		)
	)
)
